(kicad_pcb
	(version 20260206)
	(generator "pcbnew")
	(generator_version "10.0")
	(general
		(thickness 1.6)
		(legacy_teardrops no)
	)
	(paper "A4")
	(title_block
		(title "03242023_DA0F0TMBIJ0_F0T_Motherboard_J_brd_V01_OCP.brd")
		(comment 1 "Grand Teton / footprint 1335 of 6105 (J17), pads 225-291 of 291")
	)
	(layers
		(0 "F.Cu" signal "TOP")
		(4 "In1.Cu" signal "GND")
		(6 "In2.Cu" signal "IN1")
		(8 "In3.Cu" signal "GND1")
		(10 "In4.Cu" signal "IN2")
		(12 "In5.Cu" signal "GND2")
		(14 "In6.Cu" signal "IN3")
		(16 "In7.Cu" signal "GND3")
		(18 "In8.Cu" signal "VCC")
		(20 "In9.Cu" signal "VCC1")
		(22 "In10.Cu" signal "GND4")
		(24 "In11.Cu" signal "IN4")
		(26 "In12.Cu" signal "GND5")
		(28 "In13.Cu" signal "IN5")
		(30 "In14.Cu" signal "GND6")
		(32 "In15.Cu" signal "IN6")
		(34 "In16.Cu" signal "GND7")
		(2 "B.Cu" signal "BOTTOM")
		(9 "F.Adhes" user "F.Adhesive")
		(11 "B.Adhes" user "B.Adhesive")
		(13 "F.Paste" user "Package Geometry/Pastemask Top")
		(15 "B.Paste" user "Package Geometry/Pastemask Bottom")
		(5 "F.SilkS" user "Ref Des/Silkscreen Top")
		(7 "B.SilkS" user "Ref Des/Silkscreen Bottom")
		(1 "F.Mask" user "Board Geometry/Soldermask Top")
		(3 "B.Mask" user "Board Geometry/Soldermask Bottom")
		(17 "Dwgs.User" user "User.Drawings")
		(19 "Cmts.User" user "User.Comments")
		(21 "Eco1.User" user "User.Eco1")
		(23 "Eco2.User" user "User.Eco2")
		(25 "Edge.Cuts" user "Board Geometry/Outline")
		(27 "Margin" user)
		(31 "F.CrtYd" user "Package Geometry/Place Bound Top")
		(29 "B.CrtYd" user "Package Geometry/Place Bound Bottom")
		(35 "F.Fab" user "Ref Des/Assembly Top")
		(33 "B.Fab" user "Ref Des/Assembly Bottom")
	)
	(footprint ""
		(layer "F.Cu")
		(at 55.45328 -258.091686)
		(property "Reference" "J17"
			(at -0.178562 -81.717134 0)
			(unlocked yes)
			(layer "F.SilkS")
			(effects
				(font
					(size 0.7874 0.5842)
					(thickness 0.1524)
				)
				(justify left)
			)
		)
		(property "Value" ""
			(at 0 0 0)
			(layer "F.Fab")
			(effects
				(font
					(size 1.27 1.27)
				)
			)
		)
		(duplicate_pad_numbers_are_jumpers no)
		(pad "225" smd rect
			(at 2.050034 9.774936 270)
			(size 0.519938 1.4986)
			(layers "F.Cu" "F.Mask" "F.Paste")
			(net "M_A_CPU1_SB_CA<5>")
		)
		(pad "226" smd rect
			(at 2.050034 10.625074 270)
			(size 0.519938 1.4986)
			(layers "F.Cu" "F.Mask" "F.Paste")
			(net "GND")
		)
		(pad "227" smd rect
			(at 2.050034 11.474958 270)
			(size 0.519938 1.4986)
			(layers "F.Cu" "F.Mask" "F.Paste")
			(net "M_A_CPU1_SB_PAR")
		)
		(pad "228" smd rect
			(at 2.050034 12.325096 270)
			(size 0.519938 1.4986)
			(layers "F.Cu" "F.Mask" "F.Paste")
			(net "GND")
		)
		(pad "229" smd rect
			(at 2.050034 13.17498 270)
			(size 0.519938 1.4986)
			(layers "F.Cu" "F.Mask" "F.Paste")
			(net "M_A_CPU1_SB_CS_N<1>")
		)
		(pad "230" smd rect
			(at 2.050034 14.025118 270)
			(size 0.519938 1.4986)
			(layers "F.Cu" "F.Mask" "F.Paste")
			(net "GND")
		)
		(pad "231" smd rect
			(at 2.050034 14.875002 270)
			(size 0.519938 1.4986)
			(layers "F.Cu" "F.Mask" "F.Paste")
			(net "TP_CHA_CPU1_DIMM1_FRU_5")
		)
		(pad "232" smd rect
			(at 2.050034 15.724886 270)
			(size 0.519938 1.4986)
			(layers "F.Cu" "F.Mask" "F.Paste")
			(net "TP_CHA_CPU1_DIMM1_FRU_6")
		)
		(pad "233" smd rect
			(at 2.050034 16.575024 270)
			(size 0.519938 1.4986)
			(layers "F.Cu" "F.Mask" "F.Paste")
			(net "GND")
		)
		(pad "234" smd rect
			(at 2.050034 17.424908 270)
			(size 0.519938 1.4986)
			(layers "F.Cu" "F.Mask" "F.Paste")
			(net "M_A_CPU1_SB_CB<6>")
		)
		(pad "235" smd rect
			(at 2.050034 18.275046 270)
			(size 0.519938 1.4986)
			(layers "F.Cu" "F.Mask" "F.Paste")
			(net "GND")
		)
		(pad "236" smd rect
			(at 2.050034 19.12493 270)
			(size 0.519938 1.4986)
			(layers "F.Cu" "F.Mask" "F.Paste")
			(net "M_A_CPU1_SB_CB<7>")
		)
		(pad "237" smd rect
			(at 2.050034 19.975068 270)
			(size 0.519938 1.4986)
			(layers "F.Cu" "F.Mask" "F.Paste")
			(net "GND")
		)
		(pad "238" smd rect
			(at 2.050034 20.824952 270)
			(size 0.519938 1.4986)
			(layers "F.Cu" "F.Mask" "F.Paste")
			(net "M_A_CPU1_SB_DQS_DN<4>")
		)
		(pad "239" smd rect
			(at 2.050034 21.67509 270)
			(size 0.519938 1.4986)
			(layers "F.Cu" "F.Mask" "F.Paste")
			(net "M_A_CPU1_SB_DQS_DP<4>")
		)
		(pad "240" smd rect
			(at 2.050034 22.524974 270)
			(size 0.519938 1.4986)
			(layers "F.Cu" "F.Mask" "F.Paste")
			(net "GND")
		)
		(pad "241" smd rect
			(at 2.050034 23.375112 270)
			(size 0.519938 1.4986)
			(layers "F.Cu" "F.Mask" "F.Paste")
			(net "M_A_CPU1_SB_CB<2>")
		)
		(pad "242" smd rect
			(at 2.050034 24.224996 270)
			(size 0.519938 1.4986)
			(layers "F.Cu" "F.Mask" "F.Paste")
			(net "GND")
		)
		(pad "243" smd rect
			(at 2.050034 25.07488 270)
			(size 0.519938 1.4986)
			(layers "F.Cu" "F.Mask" "F.Paste")
			(net "M_A_CPU1_SB_CB<3>")
		)
		(pad "244" smd rect
			(at 2.050034 25.925018 270)
			(size 0.519938 1.4986)
			(layers "F.Cu" "F.Mask" "F.Paste")
			(net "GND")
		)
		(pad "245" smd rect
			(at 2.050034 26.774902 270)
			(size 0.519938 1.4986)
			(layers "F.Cu" "F.Mask" "F.Paste")
			(net "M_A_CPU1_SB_DQ<2>")
		)
		(pad "246" smd rect
			(at 2.050034 27.62504 270)
			(size 0.519938 1.4986)
			(layers "F.Cu" "F.Mask" "F.Paste")
			(net "GND")
		)
		(pad "247" smd rect
			(at 2.050034 28.474924 270)
			(size 0.519938 1.4986)
			(layers "F.Cu" "F.Mask" "F.Paste")
			(net "M_A_CPU1_SB_DQ<3>")
		)
		(pad "248" smd rect
			(at 2.050034 29.325062 270)
			(size 0.519938 1.4986)
			(layers "F.Cu" "F.Mask" "F.Paste")
			(net "GND")
		)
		(pad "249" smd rect
			(at 2.050034 30.174946 270)
			(size 0.519938 1.4986)
			(layers "F.Cu" "F.Mask" "F.Paste")
			(net "M_A_CPU1_SB_DQS_DN<5>")
		)
		(pad "250" smd rect
			(at 2.050034 31.025084 270)
			(size 0.519938 1.4986)
			(layers "F.Cu" "F.Mask" "F.Paste")
			(net "M_A_CPU1_SB_DQS_DP<5>")
		)
		(pad "251" smd rect
			(at 2.050034 31.874968 270)
			(size 0.519938 1.4986)
			(layers "F.Cu" "F.Mask" "F.Paste")
			(net "GND")
		)
		(pad "252" smd rect
			(at 2.050034 32.725106 270)
			(size 0.519938 1.4986)
			(layers "F.Cu" "F.Mask" "F.Paste")
			(net "M_A_CPU1_SB_DQ<6>")
		)
		(pad "253" smd rect
			(at 2.050034 33.57499 270)
			(size 0.519938 1.4986)
			(layers "F.Cu" "F.Mask" "F.Paste")
			(net "GND")
		)
		(pad "254" smd rect
			(at 2.050034 34.425128 270)
			(size 0.519938 1.4986)
			(layers "F.Cu" "F.Mask" "F.Paste")
			(net "M_A_CPU1_SB_DQ<7>")
		)
		(pad "255" smd rect
			(at 2.050034 35.275012 270)
			(size 0.519938 1.4986)
			(layers "F.Cu" "F.Mask" "F.Paste")
			(net "GND")
		)
		(pad "256" smd rect
			(at 2.050034 36.124896 270)
			(size 0.519938 1.4986)
			(layers "F.Cu" "F.Mask" "F.Paste")
			(net "M_A_CPU1_SB_DQ<10>")
		)
		(pad "257" smd rect
			(at 2.050034 36.975034 270)
			(size 0.519938 1.4986)
			(layers "F.Cu" "F.Mask" "F.Paste")
			(net "GND")
		)
		(pad "258" smd rect
			(at 2.050034 37.824918 270)
			(size 0.519938 1.4986)
			(layers "F.Cu" "F.Mask" "F.Paste")
			(net "M_A_CPU1_SB_DQ<11>")
		)
		(pad "259" smd rect
			(at 2.050034 38.675056 270)
			(size 0.519938 1.4986)
			(layers "F.Cu" "F.Mask" "F.Paste")
			(net "GND")
		)
		(pad "260" smd rect
			(at 2.050034 39.52494 270)
			(size 0.519938 1.4986)
			(layers "F.Cu" "F.Mask" "F.Paste")
			(net "M_A_CPU1_SB_DQS_DN<6>")
		)
		(pad "261" smd rect
			(at 2.050034 40.375078 270)
			(size 0.519938 1.4986)
			(layers "F.Cu" "F.Mask" "F.Paste")
			(net "M_A_CPU1_SB_DQS_DP<6>")
		)
		(pad "262" smd rect
			(at 2.050034 41.224962 270)
			(size 0.519938 1.4986)
			(layers "F.Cu" "F.Mask" "F.Paste")
			(net "GND")
		)
		(pad "263" smd rect
			(at 2.050034 42.0751 270)
			(size 0.519938 1.4986)
			(layers "F.Cu" "F.Mask" "F.Paste")
			(net "M_A_CPU1_SB_DQ<14>")
		)
		(pad "264" smd rect
			(at 2.050034 42.924984 270)
			(size 0.519938 1.4986)
			(layers "F.Cu" "F.Mask" "F.Paste")
			(net "GND")
		)
		(pad "265" smd rect
			(at 2.050034 43.775122 270)
			(size 0.519938 1.4986)
			(layers "F.Cu" "F.Mask" "F.Paste")
			(net "M_A_CPU1_SB_DQ<15>")
		)
		(pad "266" smd rect
			(at 2.050034 44.625006 270)
			(size 0.519938 1.4986)
			(layers "F.Cu" "F.Mask" "F.Paste")
			(net "GND")
		)
		(pad "267" smd rect
			(at 2.050034 45.47489 270)
			(size 0.519938 1.4986)
			(layers "F.Cu" "F.Mask" "F.Paste")
			(net "M_A_CPU1_SB_DQ<18>")
		)
		(pad "268" smd rect
			(at 2.050034 46.325028 270)
			(size 0.519938 1.4986)
			(layers "F.Cu" "F.Mask" "F.Paste")
			(net "GND")
		)
		(pad "269" smd rect
			(at 2.050034 47.174912 270)
			(size 0.519938 1.4986)
			(layers "F.Cu" "F.Mask" "F.Paste")
			(net "M_A_CPU1_SB_DQ<19>")
		)
		(pad "270" smd rect
			(at 2.050034 48.02505 270)
			(size 0.519938 1.4986)
			(layers "F.Cu" "F.Mask" "F.Paste")
			(net "GND")
		)
		(pad "271" smd rect
			(at 2.050034 48.874934 270)
			(size 0.519938 1.4986)
			(layers "F.Cu" "F.Mask" "F.Paste")
			(net "M_A_CPU1_SB_DQS_DN<7>")
		)
		(pad "272" smd rect
			(at 2.050034 49.725072 270)
			(size 0.519938 1.4986)
			(layers "F.Cu" "F.Mask" "F.Paste")
			(net "M_A_CPU1_SB_DQS_DP<7>")
		)
		(pad "273" smd rect
			(at 2.050034 50.574956 270)
			(size 0.519938 1.4986)
			(layers "F.Cu" "F.Mask" "F.Paste")
			(net "GND")
		)
		(pad "274" smd rect
			(at 2.050034 51.425094 270)
			(size 0.519938 1.4986)
			(layers "F.Cu" "F.Mask" "F.Paste")
			(net "M_A_CPU1_SB_DQ<22>")
		)
		(pad "275" smd rect
			(at 2.050034 52.274978 270)
			(size 0.519938 1.4986)
			(layers "F.Cu" "F.Mask" "F.Paste")
			(net "GND")
		)
		(pad "276" smd rect
			(at 2.050034 53.125116 270)
			(size 0.519938 1.4986)
			(layers "F.Cu" "F.Mask" "F.Paste")
			(net "M_A_CPU1_SB_DQ<23>")
		)
		(pad "277" smd rect
			(at 2.050034 53.975 270)
			(size 0.519938 1.4986)
			(layers "F.Cu" "F.Mask" "F.Paste")
			(net "GND")
		)
		(pad "278" smd rect
			(at 2.050034 54.824884 270)
			(size 0.519938 1.4986)
			(layers "F.Cu" "F.Mask" "F.Paste")
			(net "M_A_CPU1_SB_DQ<26>")
		)
		(pad "279" smd rect
			(at 2.050034 55.675022 270)
			(size 0.519938 1.4986)
			(layers "F.Cu" "F.Mask" "F.Paste")
			(net "GND")
		)
		(pad "280" smd rect
			(at 2.050034 56.524906 270)
			(size 0.519938 1.4986)
			(layers "F.Cu" "F.Mask" "F.Paste")
			(net "M_A_CPU1_SB_DQ<27>")
		)
		(pad "281" smd rect
			(at 2.050034 57.375044 270)
			(size 0.519938 1.4986)
			(layers "F.Cu" "F.Mask" "F.Paste")
			(net "GND")
		)
		(pad "282" smd rect
			(at 2.050034 58.224928 270)
			(size 0.519938 1.4986)
			(layers "F.Cu" "F.Mask" "F.Paste")
			(net "M_A_CPU1_SB_DQS_DN<8>")
		)
		(pad "283" smd rect
			(at 2.050034 59.075066 270)
			(size 0.519938 1.4986)
			(layers "F.Cu" "F.Mask" "F.Paste")
			(net "M_A_CPU1_SB_DQS_DP<8>")
		)
		(pad "284" smd rect
			(at 2.050034 59.92495 270)
			(size 0.519938 1.4986)
			(layers "F.Cu" "F.Mask" "F.Paste")
			(net "GND")
		)
		(pad "285" smd rect
			(at 2.050034 60.775088 270)
			(size 0.519938 1.4986)
			(layers "F.Cu" "F.Mask" "F.Paste")
			(net "M_A_CPU1_SB_DQ<30>")
		)
		(pad "286" smd rect
			(at 2.050034 61.624972 270)
			(size 0.519938 1.4986)
			(layers "F.Cu" "F.Mask" "F.Paste")
			(net "GND")
		)
		(pad "287" smd rect
			(at 2.050034 62.47511 270)
			(size 0.519938 1.4986)
			(layers "F.Cu" "F.Mask" "F.Paste")
			(net "M_A_CPU1_SB_DQ<31>")
		)
		(pad "288" smd rect
			(at 2.050034 63.324994 270)
			(size 0.519938 1.4986)
			(layers "F.Cu" "F.Mask" "F.Paste")
			(net "GND")
		)
		(pad "G1" thru_hole oval
			(at 0 -68.97497)
			(size 2.8194 1.5748)
			(drill oval 2.4384 1.1938)
			(layers "*.Cu" "*.Mask")
			(remove_unused_layers no)
			(net "GND")
			(clearance 0.127)
			(thermal_gap 0.127)
		)
		(pad "G2" thru_hole oval
			(at 0 3.875024)
			(size 2.8194 1.5748)
			(drill oval 2.4384 1.1938)
			(layers "*.Cu" "*.Mask")
			(remove_unused_layers no)
			(net "GND")
			(clearance 0.127)
			(thermal_gap 0.127)
		)
		(pad "G3" thru_hole oval
			(at 0 68.97497)
			(size 2.8194 1.5748)
			(drill oval 2.4384 1.1938)
			(layers "*.Cu" "*.Mask")
			(remove_unused_layers no)
			(net "GND")
			(clearance 0.127)
			(thermal_gap 0.127)
		)
	)
)
